# TIMECARD (Time Appliance Project (Time Card)) — schematic netlist excerpt (pin names and nets, part order shuffled) for the footprints in the layout excerpt that follows; sources: Cadence DE-HDL packaged netlist, KiCad conversion of R4006-B0001-02_R01.brd

R120  RESISTOR  100OHM 1%  pkg SMC_0402R_H016  page 23 : \1\ = ANT1_OUT ; \2\ = UNNAMED_12_74HCT2G125DPTSSOP8_6
C255  CAPACITOR  0.1UF 25V 10%  pkg SMC_0402R_H022  page 29 : \1\ = XP12R0V ; \2\ = SG

(kicad_pcb
	(version 20260206)
	(generator "pcbnew")
	(generator_version "10.0")
	(general
		(thickness 1.6)
		(legacy_teardrops no)
	)
	(paper "A4")
	(title_block
		(title "timecard-production-celestica-r4006 — R4006-B0001-02_R01.brd")
		(comment 1 "Time Appliance Project (Time Card) / footprints 602-603 of 1113")
	)
	(layers
		(0 "F.Cu" signal "TOP")
		(4 "In1.Cu" signal "L02_GND1")
		(6 "In2.Cu" signal "L03_SIG1")
		(8 "In3.Cu" signal "L04_GND2")
		(10 "In4.Cu" signal "L05_VCC1")
		(12 "In5.Cu" signal "L06_VCC2")
		(14 "In6.Cu" signal "L07_GND3")
		(16 "In7.Cu" signal "L08_SIG2")
		(18 "In8.Cu" signal "L09_GND4")
		(2 "B.Cu" signal "BOTTOM")
		(9 "F.Adhes" user "F.Adhesive")
		(11 "B.Adhes" user "B.Adhesive")
		(13 "F.Paste" user "Package Geometry/Pastemask Top")
		(15 "B.Paste" user "Package Geometry/Pastemask Bottom")
		(5 "F.SilkS" user "Ref Des/Silkscreen Top")
		(7 "B.SilkS" user "Ref Des/Silkscreen Bottom")
		(1 "F.Mask" user "Board Geometry/Soldermask Top")
		(3 "B.Mask" user "Board Geometry/Soldermask Bottom")
		(17 "Dwgs.User" user "User.Drawings")
		(19 "Cmts.User" user "User.Comments")
		(21 "Eco1.User" user "User.Eco1")
		(23 "Eco2.User" user "User.Eco2")
		(25 "Edge.Cuts" user "Board Geometry/Outline")
		(27 "Margin" user)
		(31 "F.CrtYd" user "Package Geometry/Place Bound Top")
		(29 "B.CrtYd" user "Package Geometry/Place Bound Bottom")
		(35 "F.Fab" user "Ref Des/Assembly Top")
		(33 "B.Fab" user "Ref Des/Assembly Bottom")
	)
	(footprint ""
		(layer "F.Cu")
		(at 13.462 -66.167 -90)
		(property "Reference" "R120"
			(at -4.953 0.59563 90)
			(unlocked yes)
			(layer "F.SilkS")
			(effects
				(font
					(size 0.7874 0.5842)
					(thickness 0.1524)
				)
			)
		)
		(property "Value" "VAL*"
			(at 0.02032 2.13233 270)
			(unlocked yes)
			(layer "F.Fab")
			(hide yes)
			(effects
				(font
					(size 0.7874 0.5842)
					(thickness 0.1524)
				)
			)
		)
		(property "Tolerance" "TOL*"
			(at 0.044704 3.05435 270)
			(unlocked yes)
			(layer "Cmts.User")
			(hide yes)
			(effects
				(font
					(size 0.7874 0.5842)
					(thickness 0.1524)
				)
			)
		)
		(property "User Part Number" "PARTNUM*"
			(at 0.02032 4.024884 270)
			(unlocked yes)
			(layer "Cmts.User")
			(hide yes)
			(effects
				(font
					(size 0.7874 0.5842)
					(thickness 0.1524)
				)
			)
		)
		(property "Device Type" "RESISTOR-G155-11000-01,100OHM,A"
			(at 0.008382 1.210564 270)
			(unlocked yes)
			(layer "F.Fab")
			(hide yes)
			(effects
				(font
					(size 0.7874 0.5842)
					(thickness 0.1524)
				)
			)
		)
		(duplicate_pad_numbers_are_jumpers no)
		(fp_line
			(start -1.143 0.5588)
			(end 1.143 0.5588)
			(stroke
				(width 0.1)
				(type default)
			)
			(layer "F.SilkS")
		)
		(fp_line
			(start 1.143 0.5588)
			(end 1.143 -0.5588)
			(stroke
				(width 0.1)
				(type default)
			)
			(layer "F.SilkS")
		)
		(fp_line
			(start -1.143 -0.5588)
			(end -1.143 0.5588)
			(stroke
				(width 0.1)
				(type default)
			)
			(layer "F.SilkS")
		)
		(fp_line
			(start 1.143 -0.5588)
			(end -1.143 -0.5588)
			(stroke
				(width 0.1)
				(type default)
			)
			(layer "F.SilkS")
		)
		(fp_poly
			(pts
				(xy -1.143 0.5588) (xy 1.143 0.5588) (xy 1.143 -0.5588) (xy -1.143 -0.5588)
			)
			(stroke
				(width 0)
				(type default)
			)
			(fill no)
			(layer "F.CrtYd")
		)
		(fp_line
			(start -0.508 0.3048)
			(end 0.508 0.3048)
			(stroke
				(width 0.1)
				(type default)
			)
			(layer "F.Fab")
		)
		(fp_line
			(start 0.508 0.3048)
			(end 0.508 -0.3048)
			(stroke
				(width 0.1)
				(type default)
			)
			(layer "F.Fab")
		)
		(fp_line
			(start -0.508 -0.3048)
			(end -0.508 0.3048)
			(stroke
				(width 0.1)
				(type default)
			)
			(layer "F.Fab")
		)
		(fp_line
			(start 0.508 -0.3048)
			(end -0.508 -0.3048)
			(stroke
				(width 0.1)
				(type default)
			)
			(layer "F.Fab")
		)
		(pad "1" smd rect
			(at -0.5334 0 270)
			(size 0.7112 0.6096)
			(layers "F.Cu" "F.Mask" "F.Paste")
			(net "ANT1_OUT")
		)
		(pad "2" smd rect
			(at 0.5334 0 270)
			(size 0.7112 0.6096)
			(layers "F.Cu" "F.Mask" "F.Paste")
			(net "UNNAMED_12_74HCT2G125DPTSSOP8_6")
		)
		(zone
			(layer "F.Cu")
			(hatch none 0.5)
			(connect_pads
				(clearance 0)
			)
			(min_thickness 0.25)
			(keepout
				(tracks allowed)
				(vias not_allowed)
				(pads allowed)
				(copperpour not_allowed)
				(footprints allowed)
			)
			(placement
				(enabled no)
				(sheetname "")
			)
			(fill
				(thermal_gap 0.5)
				(thermal_bridge_width 0.5)
				(island_removal_mode 0)
			)
			(polygon
				(pts
					(xy 13.1572 -66.2432) (xy 13.1572 -66.0908) (xy 13.7668 -66.0908) (xy 13.7668 -66.2432)
				)
			)
		)
		(zone
			(layer "F.Cu")
			(hatch none 0.5)
			(connect_pads
				(clearance 0)
			)
			(min_thickness 0.25)
			(keepout
				(tracks not_allowed)
				(vias allowed)
				(pads allowed)
				(copperpour not_allowed)
				(footprints allowed)
			)
			(placement
				(enabled no)
				(sheetname "")
			)
			(fill
				(thermal_gap 0.5)
				(thermal_bridge_width 0.5)
				(island_removal_mode 0)
			)
			(polygon
				(pts
					(xy 13.1572 -66.2432) (xy 13.1572 -66.0908) (xy 13.7668 -66.0908) (xy 13.7668 -66.2432)
				)
			)
		)
	)
	(footprint ""
		(layer "F.Cu")
		(at 135.4074 -57.3786 -90)
		(property "Reference" "C255"
			(at -0.4064 2.14503 90)
			(unlocked yes)
			(layer "F.SilkS")
			(effects
				(font
					(size 0.7874 0.5842)
					(thickness 0.1524)
				)
			)
		)
		(property "Value" "VAL*"
			(at 0.0762 2.067306 270)
			(unlocked yes)
			(layer "F.Fab")
			(hide yes)
			(effects
				(font
					(size 0.7874 0.5842)
					(thickness 0.1524)
				)
			)
		)
		(property "Device Type" "CAPACITOR-G105-0B104-EK,0.1UF,A"
			(at 0.0508 1.127506 270)
			(unlocked yes)
			(layer "F.Fab")
			(hide yes)
			(effects
				(font
					(size 0.7874 0.5842)
					(thickness 0.1524)
				)
			)
		)
		(property "User Part Number" "PARTNUM*"
			(at 0.1016 4.023106 270)
			(unlocked yes)
			(layer "Cmts.User")
			(hide yes)
			(effects
				(font
					(size 0.7874 0.5842)
					(thickness 0.1524)
				)
			)
		)
		(property "Tolerance" "TOL*"
			(at 0.0762 3.032506 270)
			(unlocked yes)
			(layer "Cmts.User")
			(hide yes)
			(effects
				(font
					(size 0.7874 0.5842)
					(thickness 0.1524)
				)
			)
		)
		(duplicate_pad_numbers_are_jumpers no)
		(fp_line
			(start -1.143 0.5588)
			(end 1.143 0.5588)
			(stroke
				(width 0.1)
				(type default)
			)
			(layer "F.SilkS")
		)
		(fp_line
			(start 1.143 0.5588)
			(end 1.143 -0.5588)
			(stroke
				(width 0.1)
				(type default)
			)
			(layer "F.SilkS")
		)
		(fp_line
			(start -1.143 -0.5588)
			(end -1.143 0.5588)
			(stroke
				(width 0.1)
				(type default)
			)
			(layer "F.SilkS")
		)
		(fp_line
			(start 1.143 -0.5588)
			(end -1.143 -0.5588)
			(stroke
				(width 0.1)
				(type default)
			)
			(layer "F.SilkS")
		)
		(fp_rect
			(start -1.143 -0.5588)
			(end 1.143 0.5588)
			(stroke
				(width 0)
				(type default)
			)
			(fill no)
			(layer "F.CrtYd")
		)
		(fp_line
			(start -0.508 0.3048)
			(end 0.508 0.3048)
			(stroke
				(width 0.1)
				(type default)
			)
			(layer "F.Fab")
		)
		(fp_line
			(start 0.508 0.3048)
			(end 0.508 -0.3048)
			(stroke
				(width 0.1)
				(type default)
			)
			(layer "F.Fab")
		)
		(fp_line
			(start -0.508 -0.3048)
			(end -0.508 0.3048)
			(stroke
				(width 0.1)
				(type default)
			)
			(layer "F.Fab")
		)
		(fp_line
			(start 0.508 -0.3048)
			(end -0.508 -0.3048)
			(stroke
				(width 0.1)
				(type default)
			)
			(layer "F.Fab")
		)
		(pad "1" smd rect
			(at -0.5334 0 270)
			(size 0.7112 0.6096)
			(layers "F.Cu" "F.Mask" "F.Paste")
			(net "XP12R0V")
		)
		(pad "2" smd rect
			(at 0.5334 0 270)
			(size 0.7112 0.6096)
			(layers "F.Cu" "F.Mask" "F.Paste")
			(net "SG")
		)
		(zone
			(layer "F.Cu")
			(hatch none 0.5)
			(connect_pads
				(clearance 0)
			)
			(min_thickness 0.25)
			(keepout
				(tracks allowed)
				(vias not_allowed)
				(pads allowed)
				(copperpour not_allowed)
				(footprints allowed)
			)
			(placement
				(enabled no)
				(sheetname "")
			)
			(fill
				(thermal_gap 0.5)
				(thermal_bridge_width 0.5)
				(island_removal_mode 0)
			)
			(polygon
				(pts
					(xy 135.7122 -57.4548) (xy 135.1026 -57.4548) (xy 135.1026 -57.3024) (xy 135.7122 -57.3024)
				)
			)
		)
	)
)
